# S9S_MB_2U (Grand Teton) — schematic netlist excerpt (pin names and nets, part order shuffled) for the footprints in the layout excerpt that follows; sources: Cadence DE-HDL packaged netlist, KiCad conversion of 03242023_DA0F0TMBIJ0_F0T_Motherboard_J_brd_V01_OCP.brd

R884  Q_RES  33.2 1% CHIP  pkg 0402LF  page 114 : A = PWRGD_CHD_CPU0_DIMM2 ; B = PWRGD_FAIL_CPU0_CD
C353  Q_CAP  47UF 4V 20% X6S  pkg C0805  page 78 : A = PVCCIN_CPU1 ; B = GND
PC1241  Q_CAP  22UF 4V 20% X6S  pkg C0805  page 263 : A = P1V8_PCH_AUX ; B = GND

(kicad_pcb
	(version 20260206)
	(generator "pcbnew")
	(generator_version "10.0")
	(general
		(thickness 1.6)
		(legacy_teardrops no)
	)
	(paper "A4")
	(title_block
		(title "03242023_DA0F0TMBIJ0_F0T_Motherboard_J_brd_V01_OCP.brd")
		(comment 1 "Grand Teton / footprints 5515-5517 of 6105")
	)
	(layers
		(0 "F.Cu" signal "TOP")
		(4 "In1.Cu" signal "GND")
		(6 "In2.Cu" signal "IN1")
		(8 "In3.Cu" signal "GND1")
		(10 "In4.Cu" signal "IN2")
		(12 "In5.Cu" signal "GND2")
		(14 "In6.Cu" signal "IN3")
		(16 "In7.Cu" signal "GND3")
		(18 "In8.Cu" signal "VCC")
		(20 "In9.Cu" signal "VCC1")
		(22 "In10.Cu" signal "GND4")
		(24 "In11.Cu" signal "IN4")
		(26 "In12.Cu" signal "GND5")
		(28 "In13.Cu" signal "IN5")
		(30 "In14.Cu" signal "GND6")
		(32 "In15.Cu" signal "IN6")
		(34 "In16.Cu" signal "GND7")
		(2 "B.Cu" signal "BOTTOM")
		(9 "F.Adhes" user "F.Adhesive")
		(11 "B.Adhes" user "B.Adhesive")
		(13 "F.Paste" user "Package Geometry/Pastemask Top")
		(15 "B.Paste" user "Package Geometry/Pastemask Bottom")
		(5 "F.SilkS" user "Ref Des/Silkscreen Top")
		(7 "B.SilkS" user "Ref Des/Silkscreen Bottom")
		(1 "F.Mask" user "Board Geometry/Soldermask Top")
		(3 "B.Mask" user "Board Geometry/Soldermask Bottom")
		(17 "Dwgs.User" user "User.Drawings")
		(19 "Cmts.User" user "User.Comments")
		(21 "Eco1.User" user "User.Eco1")
		(23 "Eco2.User" user "User.Eco2")
		(25 "Edge.Cuts" user "Board Geometry/Outline")
		(27 "Margin" user)
		(31 "F.CrtYd" user "Package Geometry/Place Bound Top")
		(29 "B.CrtYd" user "Package Geometry/Place Bound Bottom")
		(35 "F.Fab" user "Ref Des/Assembly Top")
		(33 "B.Fab" user "Ref Des/Assembly Bottom")
	)
	(footprint ""
		(layer "B.Cu")
		(at 267.336016 -318.937894 90)
		(property "Reference" "R884"
			(at 0 0 90)
			(layer "B.SilkS")
			(hide yes)
			(effects
				(font
					(size 1.27 1.27)
				)
				(justify mirror)
			)
		)
		(property "Value" ""
			(at 0 0 90)
			(layer "B.Fab")
			(effects
				(font
					(size 1.27 1.27)
				)
				(justify mirror)
			)
		)
		(duplicate_pad_numbers_are_jumpers no)
		(fp_line
			(start 0.7874 -0.4064)
			(end -0.7874 -0.4064)
			(stroke
				(width 0.1524)
				(type default)
			)
			(layer "B.SilkS")
		)
		(fp_line
			(start -0.7874 -0.4064)
			(end -0.7874 0.4064)
			(stroke
				(width 0.1524)
				(type default)
			)
			(layer "B.SilkS")
		)
		(fp_line
			(start 0.7874 0.4064)
			(end 0.7874 -0.4064)
			(stroke
				(width 0.1524)
				(type default)
			)
			(layer "B.SilkS")
		)
		(fp_line
			(start -0.7874 0.4064)
			(end 0.7874 0.4064)
			(stroke
				(width 0.1524)
				(type default)
			)
			(layer "B.SilkS")
		)
		(fp_line
			(start 0.67945 -0.305054)
			(end 0.12065 -0.305054)
			(stroke
				(width 0.1)
				(type default)
			)
			(layer "B.Fab")
		)
		(fp_line
			(start 0.12065 -0.305054)
			(end 0.12065 -0.2794)
			(stroke
				(width 0.1)
				(type default)
			)
			(layer "B.Fab")
		)
		(fp_line
			(start -0.12065 -0.3048)
			(end -0.67945 -0.3048)
			(stroke
				(width 0.1)
				(type default)
			)
			(layer "B.Fab")
		)
		(fp_line
			(start -0.67945 -0.3048)
			(end -0.67945 0.3048)
			(stroke
				(width 0.1)
				(type default)
			)
			(layer "B.Fab")
		)
		(fp_line
			(start 0.12065 -0.2794)
			(end -0.12065 -0.2794)
			(stroke
				(width 0.1)
				(type default)
			)
			(layer "B.Fab")
		)
		(fp_line
			(start -0.12065 -0.2794)
			(end -0.12065 -0.3048)
			(stroke
				(width 0.1)
				(type default)
			)
			(layer "B.Fab")
		)
		(fp_line
			(start 0.12065 0.2794)
			(end 0.12065 0.3048)
			(stroke
				(width 0.1)
				(type default)
			)
			(layer "B.Fab")
		)
		(fp_line
			(start -0.120396 0.2794)
			(end 0.12065 0.2794)
			(stroke
				(width 0.1)
				(type default)
			)
			(layer "B.Fab")
		)
		(fp_line
			(start 0.67945 0.3048)
			(end 0.67945 -0.305054)
			(stroke
				(width 0.1)
				(type default)
			)
			(layer "B.Fab")
		)
		(fp_line
			(start 0.12065 0.3048)
			(end 0.67945 0.3048)
			(stroke
				(width 0.1)
				(type default)
			)
			(layer "B.Fab")
		)
		(fp_line
			(start -0.120396 0.3048)
			(end -0.120396 0.2794)
			(stroke
				(width 0.1)
				(type default)
			)
			(layer "B.Fab")
		)
		(fp_line
			(start -0.67945 0.3048)
			(end -0.120396 0.3048)
			(stroke
				(width 0.1)
				(type default)
			)
			(layer "B.Fab")
		)
		(pad "1" smd circle
			(at 0.40005 0 270)
			(size 0 0)
			(layers "B.Cu" "B.Mask" "B.Paste")
			(net "PWRGD_CHD_CPU0_DIMM2")
		)
		(pad "2" smd circle
			(at -0.40005 0 270)
			(size 0 0)
			(layers "B.Cu" "B.Mask" "B.Paste")
			(net "PWRGD_FAIL_CPU0_CD")
		)
	)
	(footprint ""
		(layer "B.Cu")
		(at 376.493532 -72.531224 180)
		(property "Reference" "PC1241"
			(at 0 0 0)
			(layer "B.SilkS")
			(hide yes)
			(effects
				(font
					(size 1.27 1.27)
				)
				(justify mirror)
			)
		)
		(property "Value" ""
			(at 0 0 0)
			(layer "B.Fab")
			(effects
				(font
					(size 1.27 1.27)
				)
				(justify mirror)
			)
		)
		(duplicate_pad_numbers_are_jumpers no)
		(fp_line
			(start 1.524 0.762)
			(end 1.524 -0.762)
			(stroke
				(width 0.1524)
				(type default)
			)
			(layer "B.SilkS")
		)
		(fp_line
			(start 1.524 -0.762)
			(end -1.524 -0.762)
			(stroke
				(width 0.1524)
				(type default)
			)
			(layer "B.SilkS")
		)
		(fp_line
			(start -1.524 0.762)
			(end 1.524 0.762)
			(stroke
				(width 0.1524)
				(type default)
			)
			(layer "B.SilkS")
		)
		(fp_line
			(start -1.524 -0.762)
			(end -1.524 0.762)
			(stroke
				(width 0.1524)
				(type default)
			)
			(layer "B.SilkS")
		)
		(fp_line
			(start 1.1049 0.724916)
			(end -1.1049 0.724916)
			(stroke
				(width 0.1)
				(type default)
			)
			(layer "B.Fab")
		)
		(fp_line
			(start 1.1049 -0.724916)
			(end 1.1049 0.724916)
			(stroke
				(width 0.1)
				(type default)
			)
			(layer "B.Fab")
		)
		(fp_line
			(start -1.1049 0.724916)
			(end -1.1049 -0.724916)
			(stroke
				(width 0.1)
				(type default)
			)
			(layer "B.Fab")
		)
		(fp_line
			(start -1.1049 -0.724916)
			(end 1.1049 -0.724916)
			(stroke
				(width 0.1)
				(type default)
			)
			(layer "B.Fab")
		)
		(pad "1" smd rect
			(at 0.889 0 180)
			(size 1.016 1.27)
			(layers "B.Cu" "B.Mask" "B.Paste")
			(net "P1V8_PCH_AUX")
		)
		(pad "2" smd rect
			(at -0.889 0 180)
			(size 1.016 1.27)
			(layers "B.Cu" "B.Mask" "B.Paste")
			(net "GND")
		)
	)
	(footprint ""
		(layer "B.Cu")
		(at 119.95912 -252.17628 -90)
		(property "Reference" "C353"
			(at 0 0 90)
			(layer "B.SilkS")
			(hide yes)
			(effects
				(font
					(size 1.27 1.27)
				)
				(justify mirror)
			)
		)
		(property "Value" ""
			(at 0 0 90)
			(layer "B.Fab")
			(effects
				(font
					(size 1.27 1.27)
				)
				(justify mirror)
			)
		)
		(duplicate_pad_numbers_are_jumpers no)
		(fp_line
			(start -1.524 0.762)
			(end 1.524 0.762)
			(stroke
				(width 0.1524)
				(type default)
			)
			(layer "B.SilkS")
		)
		(fp_line
			(start 1.524 0.762)
			(end 1.524 -0.762)
			(stroke
				(width 0.1524)
				(type default)
			)
			(layer "B.SilkS")
		)
		(fp_line
			(start -1.524 -0.762)
			(end -1.524 0.762)
			(stroke
				(width 0.1524)
				(type default)
			)
			(layer "B.SilkS")
		)
		(fp_line
			(start 1.524 -0.762)
			(end -1.524 -0.762)
			(stroke
				(width 0.1524)
				(type default)
			)
			(layer "B.SilkS")
		)
		(fp_line
			(start -1.1049 0.724916)
			(end -1.1049 -0.724916)
			(stroke
				(width 0.1)
				(type default)
			)
			(layer "B.Fab")
		)
		(fp_line
			(start 1.1049 0.724916)
			(end -1.1049 0.724916)
			(stroke
				(width 0.1)
				(type default)
			)
			(layer "B.Fab")
		)
		(fp_line
			(start -1.1049 -0.724916)
			(end 1.1049 -0.724916)
			(stroke
				(width 0.1)
				(type default)
			)
			(layer "B.Fab")
		)
		(fp_line
			(start 1.1049 -0.724916)
			(end 1.1049 0.724916)
			(stroke
				(width 0.1)
				(type default)
			)
			(layer "B.Fab")
		)
		(pad "1" smd rect
			(at 0.889 0 270)
			(size 1.016 1.27)
			(layers "B.Cu" "B.Mask" "B.Paste")
			(net "PVCCIN_CPU1")
		)
		(pad "2" smd rect
			(at -0.889 0 270)
			(size 1.016 1.27)
			(layers "B.Cu" "B.Mask" "B.Paste")
			(net "GND")
		)
	)
)
